# BASEBOARD_FAB2 (Tioga Pass) — schematic parts with pin connectivity, parts 4650–4661 of 4751; source: Cadence DE-HDL packaged netlist (pstxprt.dat, pstxnet.dat, pstchip.dat)

U2D1  SKX_EXT_B  IC  pkg BGA1  page 55  (pins 3381-3647 of 3647)
  P63  VSS(732)  GROUND  = GND
  P65  RSVD(265)  BI  = TP_CPU1_RSVD_265
  P67  VSS(1026)  GROUND  = GND
  P69  VSS(1025)  GROUND  = GND
  P71  VSS(1024)  GROUND  = GND
  P73  DDR0_DQ(27)  BI  = M_G_DQ<27>
  P75  DDR0_DQS_DP(3)  BI  = M_G_DQS_DP<3>
  P77  DDR0_DQ(29)  BI  = M_G_DQ<29>
  P79  DDR0_DQS_DN(2)  BI  = M_G_DQS_DN<2>
  P81  VSS(1023)  GROUND  = GND
  P83  VSS(1022)  GROUND  = GND
  P85  DDR0_DQS_DP(1)  BI  = M_G_DQS_DP<1>
  R2  VSS(1019)  GROUND  = GND
  R4  VSS(1018)  GROUND  = GND
  R6  UPI1_RX_DP(0)  IN  = UPI_CPU0_CPU1_P1P1_DN<0>
  R8  UPI1_RX_DP(3)  IN  = UPI_CPU0_CPU1_P1P1_DP<3>
  R10  UPI1_RX_DN(5)  IN  = UPI_CPU0_CPU1_P1P1_DN<5>
  R12  UPI1_RX_DN(9)  IN  = UPI_CPU0_CPU1_P1P1_DN<9>
  R14  VSS(1021)  GROUND  = GND
  R16  UPI1_RX_DN(10)  IN  = UPI_CPU0_CPU1_P1P1_DN<10>
  R18  VSS(1020)  GROUND  = GND
  R20  UPI1_RX_DN(14)  IN  = UPI_CPU0_CPU1_P1P1_DN<14>
  R22  VSS(1017)  GROUND  = GND
  R24  DDR0_DQS_DP(7)  BI  = M_G_DQS_DP<7>
  R26  VSS(1016)  GROUND  = GND
  R28  VSS(1015)  GROUND  = GND
  R30  DDR0_DQS_DN(6)  BI  = M_G_DQS_DN<6>
  R32  VSS(1014)  GROUND  = GND
  R34  VSS(1013)  GROUND  = GND
  R36  DDR0_DQS_DN(5)  BI  = M_G_DQS_DN<5>
  R38  VSS(1012)  GROUND  = GND
  R40  VSS(1011)  GROUND  = GND
  R42  DDR1_DQS_DP(4)  BI  = M_H_DQS_DP<4>
  R46  DDR1_CS_N(7)  OUT  = M_H_CS_N<7>
  R48  DDR1_ODT(1)  OUT  = M_H_ODT<1>
  R50  DDR1_CS_N(1)  OUT  = M_H_CS_N<1>
  R52  DDR1_MA(16)  OUT  = M_H_MA<16>
  R54  DDR1_CLK_DN(1)  OUT  = M_H_CLK_DN<1>
  R56  DDR1_CLK_DN(3)  OUT  = M_H_CLK_DN<3>
  R58  DDR1_MA(5)  OUT  = M_H_MA<5>
  R60  DDR1_MA(11)  OUT  = M_H_MA<11>
  R62  RSVD(264)  BI  = TP_CPU1_RSVD_264
  R64  DDR1_CKE(1)  OUT  = M_H_CKE<1>
  R66  RSVD(263)  BI  = TP_CPU1_RSVD_263
  R68  VSS(1010)  GROUND  = GND
  R70  DDR2_DQ(18)  BI  = M_J_DQ<18>
  R72  VSS(1009)  GROUND  = GND
  R74  DDR0_DQ(31)  BI  = M_G_DQ<31>
  R76  DDR0_DQ(25)  BI  = M_G_DQ<25>
  R78  VSS(1008)  GROUND  = GND
  R80  DDR0_DQS_DP(2)  BI  = M_G_DQS_DP<2>
  R82  DDR0_DQ(22)  BI  = M_G_DQ<22>
  R84  DDR0_DQS_DN(1)  BI  = M_G_DQS_DN<1>
  R86  VSS(1007)  GROUND  = GND
  T1  UPI0_TX_DP(1)  OUT  = UPI_CPU1_CPU0_P0P0_DN<1>
  T3  VCCIO(50)  POWER  = PVCCIO_CPU1
  T5  UPI1_RX_DN(0)  IN  = UPI_CPU0_CPU1_P1P1_DP<0>
  T7  UPI1_RX_DP(1)  IN  = UPI_CPU0_CPU1_P1P1_DP<1>
  T9  UPI1_RX_DN(3)  IN  = UPI_CPU0_CPU1_P1P1_DN<3>
  T11  UPI1_RX_DP(6)  IN  = UPI_CPU0_CPU1_P1P1_DP<6>
  T13  VSS(1006)  GROUND  = GND
  T15  UPI1_RX_DP(10)  IN  = UPI_CPU0_CPU1_P1P1_DP<10>
  T17  VSS(1005)  GROUND  = GND
  T19  UPI1_RX_DP(15)  IN  = UPI_CPU0_CPU1_P1P1_DP<15>
  T21  UPI1_RX_DP(16)  IN  = UPI_CPU0_CPU1_P1P1_DP<16>
  T23  DDR0_DQ(59)  BI  = M_G_DQ<59>
  T25  VSS(1004)  GROUND  = GND
  T27  DDR1_DQS_DN(16)  BI  = M_H_DQS_DN<16>
  T29  VSS(1003)  GROUND  = GND
  T31  VSS(1002)  GROUND  = GND
  T33  DDR2_DQS_DN(14)  BI  = M_J_DQS_DN<14>
  T35  VSS(1001)  GROUND  = GND
  T37  VSS(1000)  GROUND  = GND
  T39  DDR2_DQS_DN(13)  BI  = M_J_DQS_DN<13>
  T41  VSS(999)  GROUND  = GND
  T43  DDR1_DQ(37)  BI  = M_H_DQ<37>
  T45  DDR2_CS_N(6)  OUT  = M_J_CS_N<6>
  T47  DDR1_ODT(3)  OUT  = M_H_ODT<3>
  T49  DDR1_CS_N(5)  OUT  = M_H_CS_N<5>
  T51  DDR1_MA(14)  OUT  = M_H_MA<14>
  T53  DDR1_BA(0)  OUT  = M_H_BA<0>
  T55  DDR1_CLK_DP(1)  OUT  = M_H_CLK_DP<1>
  T57  DDR1_CLK_DP(3)  OUT  = M_H_CLK_DP<3>
  T59  DDR1_MA(6)  OUT  = M_H_MA<6>
  T61  DDR1_MA(12)  OUT  = M_H_MA<12>
  T63  DDR1_ACT_N  OUT  = M_H_ACT_N
  T65  VSS(998)  GROUND  = GND
  T67  RSVD(262)  BI  = TP_CPU1_RSVD_262
  T69  DDR2_DQ(19)  BI  = M_J_DQ<19>
  T71  DDR2_DQ(22)  BI  = M_J_DQ<22>
  T73  VSS(997)  GROUND  = GND
  T75  DDR0_DQS_DN(3)  BI  = M_G_DQS_DN<3>
  T77  VSS(996)  GROUND  = GND
  T79  DDR0_DQ(17)  BI  = M_G_DQ<17>
  T81  DDR0_DQS_DP(11)  BI  = M_G_DQS_DP<11>
  T83  VSS(995)  GROUND  = GND
  T85  VSS(994)  GROUND  = GND
  U2  VSS(993)  GROUND  = GND
  U4  VSS(992)  GROUND  = GND
  U6  VSS(991)  GROUND  = GND
  U8  UPI1_RX_DP(2)  IN  = UPI_CPU0_CPU1_P1P1_DP<2>
  U10  UPI1_RX_DP(5)  IN  = UPI_CPU0_CPU1_P1P1_DP<5>
  U12  UPI1_RX_DN(6)  IN  = UPI_CPU0_CPU1_P1P1_DN<6>
  U14  VCCIO(49)  POWER  = PVCCIO_CPU1
  U16  UPI1_RX_DN(12)  IN  = UPI_CPU0_CPU1_P1P1_DP<12>
  U18  UPI1_RX_DN(15)  IN  = UPI_CPU0_CPU1_P1P1_DN<15>
  U20  VSS(990)  GROUND  = GND
  U22  VSS(989)  GROUND  = GND
  U24  VSS(988)  GROUND  = GND
  U26  DDR1_DQ(62)  BI  = M_H_DQ<62>
  U28  DDR1_DQ(56)  BI  = M_H_DQ<56>
  U30  VSS(987)  GROUND  = GND
  U32  DDR2_DQ(46)  BI  = M_J_DQ<46>
  U34  DDR2_DQ(40)  BI  = M_J_DQ<40>
  U36  VSS(986)  GROUND  = GND
  U38  DDR2_DQ(38)  BI  = M_J_DQ<38>
  U40  DDR2_DQ(32)  BI  = M_J_DQ<32>
  U42  VSS(985)  GROUND  = GND
  U46  VCCD012(23)  POWER  = PVDDQ_GHJ
  U48  VCCD012(24)  POWER  = PVDDQ_GHJ
  U50  VCCD012(25)  POWER  = PVDDQ_GHJ
  U52  VCCD012(26)  POWER  = PVDDQ_GHJ
  U54  VCCD012(27)  POWER  = PVDDQ_GHJ
  U56  VCCD012(28)  POWER  = PVDDQ_GHJ
  U58  VCCD012(29)  POWER  = PVDDQ_GHJ
  U60  VCCD012(30)  POWER  = PVDDQ_GHJ
  U62  VCCD012(31)  POWER  = PVDDQ_GHJ
  U64  DDR012_RESET_N  OUT  = M_GHJ_RST_N
  U66  RSVD(261)  BI  = TP_CPU1_RSVD_261
  U68  VSS(984)  GROUND  = GND
  U70  VSS(983)  GROUND  = GND
  U72  DDR2_DQS_DN(11)  BI  = M_J_DQS_DN<11>
  U74  VSS(982)  GROUND  = GND
  U76  VSS(981)  GROUND  = GND
  U78  VSS(980)  GROUND  = GND
  U80  VSS(979)  GROUND  = GND
  U82  DDR0_DQS_DN(11)  BI  = M_G_DQS_DN<11>
  U84  DDR0_DQS_DN(10)  BI  = M_G_DQS_DN<10>
  U86  VSS(978)  GROUND  = GND
  V1  VSS(977)  GROUND  = GND
  V3  UPI0_TX_DN(2)  OUT  = UPI_CPU1_CPU0_P0P0_DN<2>
  V5  VSS(976)  GROUND  = GND
  V7  UPI1_RX_DN(2)  IN  = UPI_CPU0_CPU1_P1P1_DN<2>
  V9  VSS(975)  GROUND  = GND
  V11  VSS(1227)  GROUND  = GND
  V13  VSS(974)  GROUND  = GND
  V15  VSS(973)  GROUND  = GND
  V17  UPI1_RX_DP(13)  IN  = UPI_CPU0_CPU1_P1P1_DN<13>
  V19  UPI1_RX_DN(17)  IN  = UPI_CPU0_CPU1_P1P1_DN<17>
  V21  VSS(972)  GROUND  = GND
  V23  VSS(971)  GROUND  = GND
  V25  DDR1_DQ(58)  BI  = M_H_DQ<58>
  V27  DDR1_DQS_DP(16)  BI  = M_H_DQS_DP<16>
  V29  DDR1_DQ(60)  BI  = M_H_DQ<60>
  V31  DDR2_DQ(42)  BI  = M_J_DQ<42>
  V33  DDR2_DQS_DP(14)  BI  = M_J_DQS_DP<14>
  V35  DDR2_DQ(44)  BI  = M_J_DQ<44>
  V37  DDR2_DQ(34)  BI  = M_J_DQ<34>
  V39  DDR2_DQS_DP(13)  BI  = M_J_DQS_DP<13>
  V41  DDR2_DQ(36)  BI  = M_J_DQ<36>
  V43  VSS(970)  GROUND  = GND
  V45  DDR2_CS_N(7)  OUT  = M_J_CS_N<7>
  V47  DDR1_CS_N(3)  OUT  = M_H_CS_N<3>
  V49  DDR2_ODT(2)  OUT  = M_J_ODT<2>
  V51  DDR2_CS_N(0)  OUT  = M_J_CS_N<0>
  V53  DDR2_PAR  OUT  = M_J_PAR
  V55  DDR2_CLK_DP(1)  OUT  = M_J_CLK_DP<1>
  V57  DDR2_CLK_DP(3)  OUT  = M_J_CLK_DP<3>
  V59  DDR2_MA(5)  OUT  = M_J_MA<5>
  V61  DDR1_MA(7)  OUT  = M_H_MA<7>
  V63  DDR2_CKE(2)  OUT  = M_J_CKE<2>
  V65  RSVD(260)  BI  = TP_CPU1_RSVD_260
  V67  RSVD(259)  BI  = TP_CPU1_RSVD_259
  V69  DDR2_DQ(23)  BI  = M_J_DQ<23>
  V71  DDR2_DQS_DP(11)  BI  = M_J_DQS_DP<11>
  V73  VSS(969)  GROUND  = GND
  V75  VSS(968)  GROUND  = GND
  V77  VSS(967)  GROUND  = GND
  V79  DDR0_DQ(21)  BI  = M_G_DQ<21>
  V81  DDR0_DQ(16)  BI  = M_G_DQ<16>
  V83  VSS(966)  GROUND  = GND
  V85  DDR0_DQS_DP(10)  BI  = M_G_DQS_DP<10>
  W2  UPI0_TX_DP(3)  OUT  = UPI_CPU1_CPU0_P0P0_DP<3>
  W4  VCCIO(47)  POWER  = PVCCIO_CPU1
  W6  VCCIO(46)  POWER  = PVCCIO_CPU1
  W8  VSS(965)  GROUND  = GND
  W10  VCCIO(74)  POWER  = PVCCIO_CPU1
  W12  VSS(963)  GROUND  = GND
  W14  TMS  IN  = XDP_CPU_TMS
  W16  UPI1_RX_DP(12)  IN  = UPI_CPU0_CPU1_P1P1_DN<12>
  W18  UPI1_RX_DN(13)  IN  = UPI_CPU0_CPU1_P1P1_DP<13>
  W20  UPI1_RX_DP(18)  IN  = UPI_CPU0_CPU1_P1P1_DN<18>
  W22  VSS(962)  GROUND  = GND
  W24  VSS(961)  GROUND  = GND
  W26  VSS(960)  GROUND  = GND
  W28  VSS(959)  GROUND  = GND
  W30  VSS(958)  GROUND  = GND
  W32  VSS(957)  GROUND  = GND
  W34  VSS(956)  GROUND  = GND
  W36  VSS(955)  GROUND  = GND
  W38  VSS(954)  GROUND  = GND
  W40  VSS(953)  GROUND  = GND
  W42  VSS(952)  GROUND  = GND
  W46  DDR2_CS_N(2)  OUT  = M_J_CS_N<2>
  W48  DDR2_CS_N(5)  OUT  = M_J_CS_N<5>
  W50  DDR2_MA(14)  OUT  = M_J_MA<14>
  W52  DDR2_BA(0)  OUT  = M_J_BA<0>
  W54  DDR2_CLK_DN(1)  OUT  = M_J_CLK_DN<1>
  W56  DDR2_CLK_DN(3)  OUT  = M_J_CLK_DN<3>
  W58  DDR2_MA(3)  OUT  = M_J_MA<3>
  W60  DDR1_MA(8)  OUT  = M_H_MA<8>
  W62  DDR1_ALERT_N  IN  = M_H_ALERT_N
  W64  VCCD012(32)  POWER  = PVDDQ_GHJ
  W66  RSVD(258)  BI  = TP_CPU1_RSVD_258
  W68  VSS(951)  GROUND  = GND
  W70  DDR2_DQS_DP(2)  BI  = M_J_DQS_DP<2>
  W72  DDR2_DQ(16)  BI  = M_J_DQ<16>
  W74  VSS(950)  GROUND  = GND
  W76  DDR2_DQ(11)  BI  = M_J_DQ<11>
  W78  VSS(949)  GROUND  = GND
  W80  DDR0_DQ(20)  BI  = M_G_DQ<20>
  W82  VSS(948)  GROUND  = GND
  W84  DDR0_DQ(9)  BI  = M_G_DQ<9>
  W86  DDR0_DQ(8)  BI  = M_G_DQ<8>
  Y1  UPI0_TX_DN(3)  OUT  = UPI_CPU1_CPU0_P0P0_DN<3>
  Y3  UPI0_TX_DP(2)  OUT  = UPI_CPU1_CPU0_P0P0_DP<2>
  Y5  VSS(945)  GROUND  = GND
  Y7  VSS(943)  GROUND  = GND
  Y9  VSS(942)  GROUND  = GND
  Y11  BPM_N(5)  BI  = TP_XDP_CPU1_OBSDATA_B3_MBP5_N
  Y13  TRST_N  IN  = XDP_CPU_TRST_N
  Y15  VSS(947)  GROUND  = GND
  Y17  VSS(946)  GROUND  = GND
  Y19  UPI1_RX_DP(17)  IN  = UPI_CPU0_CPU1_P1P1_DP<17>
  Y21  UPI1_RX_DN(18)  IN  = UPI_CPU0_CPU1_P1P1_DP<18>
  Y23  RSVD(257)  BI  = FM_CPU1_RC_ERROR_N
  Y25  DDR1_DQ(59)  BI  = M_H_DQ<59>
  Y27  DDR1_DQS_DP(7)  BI  = M_H_DQS_DP<7>
  Y29  DDR1_DQ(61)  BI  = M_H_DQ<61>
  Y31  DDR2_DQ(43)  BI  = M_J_DQ<43>
  Y33  DDR2_DQS_DP(5)  BI  = M_J_DQS_DP<5>
  Y35  DDR2_DQ(45)  BI  = M_J_DQ<45>
  Y37  DDR2_DQ(35)  BI  = M_J_DQ<35>
  Y39  DDR2_DQS_DP(4)  BI  = M_J_DQS_DP<4>
  Y41  DDR2_DQ(37)  BI  = M_J_DQ<37>
  Y43  DDR012_RCOMP(0)  BI  = A_CPU1_GHJ_RCOMP0
  Y45  VCCD012(33)  POWER  = PVDDQ_GHJ
  Y47  VCCD012(34)  POWER  = PVDDQ_GHJ
  Y49  VCCD012(35)  POWER  = PVDDQ_GHJ
  Y51  VCCD012(36)  POWER  = PVDDQ_GHJ
  Y53  VCCD012(37)  POWER  = PVDDQ_GHJ
  Y55  VCCD012(38)  POWER  = PVDDQ_GHJ
  Y57  VCCD012(39)  POWER  = PVDDQ_GHJ
  Y59  VCCD012(40)  POWER  = PVDDQ_GHJ
  Y61  VCCD012(41)  POWER  = PVDDQ_GHJ
  Y63  VCCD012(42)  POWER  = PVDDQ_GHJ
  Y65  RSVD(256)  BI  = TP_CPU1_RSVD_256
  Y67  VSS(944)  GROUND  = GND
  Y69  DDR2_DQS_DN(2)  BI  = M_J_DQS_DN<2>
  Y71  VSS(941)  GROUND  = GND
  Y73  VSS(940)  GROUND  = GND
  Y75  DDR2_DQ(15)  BI  = M_J_DQ<15>
  Y77  DDR2_DQ(10)  BI  = M_J_DQ<10>
  Y79  VSS(939)  GROUND  = GND
  Y81  VSS(938)  GROUND  = GND
  Y83  VSS(937)  GROUND  = GND
  Y85  VSS(936)  GROUND  = GND

U2M1  NC7SB3157  IC  pkg SMLF  page 113
  1  B1  UNSPEC  = JTAG_MCP_CPU0_TDI
  2  GND  UNSPEC  = GND
  3  B0  UNSPEC  = JTAG_MCP_CPU1_TDI
  4  A  UNSPEC  = JTAG_MCP_MUX_TDI
  5  VCC  UNSPEC  = P3V3_STBY
  6  S  UNSPEC  = FM_CPU0_CD_PRES

U2P1  TTL1G07_A  74LVC1G07 IC  pkg SOP  page 185 : 2 = FM_M2_SSD_PEDET ; 4 = FM_M2_DET_LVC3

U2R1  TC7PZ14FU-GP  pkg DISCRET-GA1  page 157
  1  \1a\  IN  = FP_NMI_BTN
  2  GND  POWER  = GND
  3  \2a\  IN  = FP_NMI_BTN_OUT_N
  4  \2y\  OUT  = FP_NMI_BTN
  5  VCC  POWER  = P3V3_STBY
  6  \1y\  OUT  = FP_NMI_BTN_R_N

U2T1  PI3B3257A  IC  pkg TSSOPLF  page 154
  1  S  BI  = FM_BIOS_SPI_BMC_CTRL
  2  IA0  BI  = SPI_PCH_IO2_R1
  3  IA1  BI  = TP_SPI_SWITCH1_3
  4  YA  BI  = SPI_BIOS_SOCKET_IO2
  5  IB0  BI  = SPI_PCH_IO3_R1
  6  IB1  BI  = TP_SPI_SWITCH1_6
  7  YB  BI  = SPI_BIOS_SOCKET_IO3
  8  GND  POWER  = GND
  9  YC  BI  = TP_SPI_SWITCH1_9
  10  IC1  BI  = TP_SPI_SWITCH1_10
  11  IC0  BI  = TP_SPI_SWITCH1_11
  12  YD  BI  = TP_SPI_SWITCH1_12
  13  ID1  BI  = TP_SPI_SWITCH1_13
  14  ID0  BI  = TP_SPI_SWITCH1_14
  15  EN  IN  = GND
  16  VCC  POWER  = P3V3_STBY

U2T2  TTL1G32_A  74LVC1G32 IC  pkg SOT  page 154
  1  A  IN  = FM_BACKUP_BIOS_SEL_N
  2  B  IN  = SPI_SWITCH_CS0_N
  4  Y  OUT  = SPI_CS0_SECONDARY_N

U2T3  TTL1G32_A  74LVC1G32 IC  pkg SOT  page 154
  1  A  IN  = FM_DUAL_BIOS_SEL_N
  2  B  IN  = SPI_SWITCH_CS0_N
  4  Y  OUT  = SPI_CS0_PRIMARY_N

U2T4  GTL2014  IC  pkg SM  page 93
  1  DIR  IN  = PD_GTL2104_4_DIR
  2  B0  BI  = H_CPU1_PROCHOT_G_R_N
  3  B1  BI  = H_CPU0_PROCHOT_G_R_N
  4  VREF  POWER  = P0V7_GTL2104_5_VREF
  5  B2  BI  = H_CPU_ERR1_GTL_N
  6  B3  BI  = H_CPU_ERR0_GTL_N
  7  GND(0)  GROUND  = GND
  8  GND(1)  GROUND  = GND
  9  A3  BI  = FM_CPU_ERR0_LVT3_R_N
  10  A2  BI  = FM_CPU_ERR1_LVT3_R_N
  11  GND(2)  GROUND  = GND
  12  A1  BI  = FM_CPU0_PROCHOT_LVT3_R_N
  13  A0  BI  = FM_CPU1_PROCHOT_LVT3_R_N
  14  VCC  POWER  = P3V3

U3B1  PCA9617  IC  pkg SSOP  page 99
  1  VCCA  POWER  = PVCCIO_CPU1
  2  SCLA  IN  = SMB_DDR_KLM_SCL_G
  3  SDAA  IN  = SMB_DDR_KLM_SDA_G
  5  EN  IN  = TP_SMB_DDR_KLM_EN
  6  SDAB  OUT  = SMB_DDR_KLM_VPP_SDA_R
  7  SCLB  OUT  = SMB_DDR_KLM_VPP_SCL_R
  8  VCCB  POWER  = PVPP_KLM

U3P1  GTL2014  IC  pkg SM  page 96
  1  DIR  IN  = PU_GTL2014_1_DIR
  2  B0  BI  = PWRGD_CPU0_DRAMPWROK_DEF_G
  3  B1  BI  = PWRGD_CPU0_DRAMPWROK_ABC_G
  4  VREF  POWER  = PD_GTL2014_1_VREF
  5  B2  BI  = RST_CPU0_G_N
  6  B3  BI  = PWRGD_CPU0_G
  7  GND(0)  GROUND  = GND
  8  GND(1)  GROUND  = GND
  9  A3  BI  = PWRGD_CPU0_LVC3
  10  A2  BI  = RST_CPU0_LVC3_N
  11  GND(2)  GROUND  = GND
  12  A1  BI  = PWRGD_DRAMPWRGD
  13  A0  BI  = PWRGD_DRAMPWRGD
  14  VCC  POWER  = P3V3_STBY

U3P2  GTL2014  IC  pkg SM  page 92
  1  DIR  IN  = PD_GTL2104_DIR_1
  2  B0  BI  = PWRGD_CPUPWRGD_GTL
  3  B1  BI  = H_CPU1_FIVR_FAULT_G
  4  VREF  POWER  = P0V7_GTL2104_VREF_1
  5  B2  BI  = H_CPU_CATERR_G_N
  6  B3  BI  = H_CPU1_THERMTRIP_G_N
  7  GND(0)  GROUND  = GND
  8  GND(1)  GROUND  = GND
  9  A3  BI  = FM_CPU1_THERMTRIP_LVT3_R_N
  10  A2  BI  = FM_CPU_CATERR_LVT3_R2_N
  11  GND(2)  GROUND  = GND
  12  A1  BI  = FM_CPU1_FIVR_FAULT_R_LVT3
  13  A0  BI  = PWRGD_CPUPWRGD_R1
  14  VCC  POWER  = P3V3

U3T1  W25Q256FVFIG-GP  pkg MEMORY-G4  page 153
  1  \hold#/io3\  BI  = PU_BIOS_SPI_HOLD1_N
  2  VCC  POWER  = P3V3_STBY
  3  \reset#\  IN  = PU_SPI1_RST
  4  \nc#4\  UNSPEC  = TP_SPI_1_6
  5  \nc#5\  UNSPEC  = TP_SPI_1_5
  6  \nc#6\  UNSPEC  = TP_SPI_1_4
  7  \cs#\  IN  = SPI_CS0_SECONDARY_R_N
  8  \do/io1\  BI  = SPI_MISO_R1
  9  \wp#/io2\  BI  = PU_BIOS_SPI_WP1_N
  10  GND  POWER  = GND
  11  \nc#11\  UNSPEC  = TP_SPI_1_3
  12  \nc#12\  UNSPEC  = TP_SPI_1_2
  13  \nc#13\  UNSPEC  = TP_SPI_1_1
  14  \nc#14\  UNSPEC  = TP_SPI_1_0
  15  \di/io0\  BI  = SPI_SWITCH_MOSI_R1
  16  CLK  IN  = SPI_CLK_R1
